(kicad_pcb
	(version 20221018)
	(generator pcbnew)
	(general
    (thickness 1.7403)
  )
	(paper "A4")
	(title_block
    (title "Data Center RDIMM DDR4 Tester")
    (date "2024-09-30")
    (rev "1.2.4")
		(comment 9 "footprints 566-570 of 690")
	)
	(layers
    (0 "F.Cu" signal)
    (1 "In1.Cu" power)
    (2 "In2.Cu" signal)
    (3 "In3.Cu" power)
    (4 "In4.Cu" power)
    (5 "In5.Cu" signal)
    (6 "In6.Cu" power)
    (7 "In7.Cu" signal)
    (8 "In8.Cu" power)
    (9 "In9.Cu" signal)
    (10 "In10.Cu" power)
    (31 "B.Cu" signal)
    (32 "B.Adhes" user "B.Adhesive")
    (33 "F.Adhes" user "F.Adhesive")
    (34 "B.Paste" user)
    (35 "F.Paste" user)
    (36 "B.SilkS" user "B.Silkscreen")
    (37 "F.SilkS" user "F.Silkscreen")
    (38 "B.Mask" user)
    (39 "F.Mask" user)
    (40 "Dwgs.User" user "User.Drawings")
    (41 "Cmts.User" user "User.Comments")
    (42 "Eco1.User" user "User.Eco1")
    (43 "Eco2.User" user "User.Eco2")
    (44 "Edge.Cuts" user)
    (45 "Margin" user)
    (46 "B.CrtYd" user "B.Courtyard")
    (47 "F.CrtYd" user "F.Courtyard")
    (48 "B.Fab" user)
    (49 "F.Fab" user)
  )
	(footprint "data-center-rdimm-ddr4-tester-footprints:C_0201" (layer "B.Cu")
    (at 177.575 87.1 90)
    (descr "Capacitor SMD 0201")
    (tags "capacitor SMD 0201")
    (property "Author" "Antmicro")
    (property "Dielectric" "")
    (property "License" "Apache-2.0")
    (property "MPN" "CC0201KRX6S5BB104")
    (property "Manufacturer" "Yaego")
    (property "Sheetfile" "fpga-power.kicad_sch")
    (property "Sheetname" "FPGA power")
    (property "Val" "100n")
    (property "Voltage" "")
    (property "ki_description" " ")
    (attr smd)
    (fp_text reference "C231" (at 1.38 -0.345 270) (layer "B.SilkS")
        (effects (font (size 0.7 0.7) (thickness 0.15)) (justify left bottom mirror))
    )
    (fp_text value "C_100n_0201" (at 0 -1.4 270) (layer "B.Fab") hide
        (effects (font (size 0.7 0.7) (thickness 0.15)) (justify left bottom mirror))
    )
    (fp_text user "Author: Antmicro" (at -0.72 -5.4 270) (layer "B.Fab") hide
        (effects (font (size 0.7 0.7) (thickness 0.15)) (justify left bottom mirror))
    )
    (fp_text user "License: Apache-2.0" (at -0.72 -4.4 270) (layer "B.Fab") hide
        (effects (font (size 0.7 0.7) (thickness 0.15)) (justify left bottom mirror))
    )
    (fp_text user "${REFERENCE}" (at -0.72 -3.4 270) (layer "B.Fab") hide
        (effects (font (size 0.7 0.7) (thickness 0.15)) (justify left bottom mirror))
    )
    (fp_rect (start -0.72 0.38) (end 0.72 -0.38)
      (stroke (width 0.05) (type solid)) (fill none) (layer "B.CrtYd"))
    (fp_rect (start 0.3 -0.15) (end -0.301 0.149)
      (stroke (width 0.15) (type solid)) (fill none) (layer "B.Fab"))
    (pad "" smd roundrect (at -0.349 0.002 90) (size 0.318 0.36) (layers "B.Paste") (roundrect_rratio 0.25))
    (pad "" smd roundrect (at 0.341 0.002 90) (size 0.318 0.36) (layers "B.Paste") (roundrect_rratio 0.25))
    (pad "1" smd roundrect (at -0.321 0.002 90) (size 0.46 0.4) (layers "B.Cu" "B.Mask") (roundrect_rratio 0.25)
      (net 77 "VDDQ") (pintype "passive"))
    (pad "2" smd roundrect (at 0.32 0.002 90) (size 0.46 0.4) (layers "B.Cu" "B.Mask") (roundrect_rratio 0.25)
      (net 9 "GND") (pintype "passive"))
  )
	(footprint "data-center-rdimm-ddr4-tester-footprints:C_0201" (layer "B.Cu")
    (at 171.175 81.35 -90)
    (descr "Capacitor SMD 0201")
    (tags "capacitor SMD 0201")
    (property "Author" "Antmicro")
    (property "Dielectric" "")
    (property "License" "Apache-2.0")
    (property "MPN" "CC0201KRX6S5BB104")
    (property "Manufacturer" "Yaego")
    (property "Sheetfile" "fpga-power.kicad_sch")
    (property "Sheetname" "FPGA power")
    (property "Val" "100n")
    (property "Voltage" "")
    (property "ki_description" " ")
    (attr smd)
    (fp_text reference "C91" (at -1.06 0.465 90) (layer "B.SilkS")
        (effects (font (size 0.7 0.7) (thickness 0.15)) (justify left bottom mirror))
    )
    (fp_text value "C_100n_0201" (at 0 -1.4 90) (layer "B.Fab") hide
        (effects (font (size 0.7 0.7) (thickness 0.15)) (justify left bottom mirror))
    )
    (fp_text user "${REFERENCE}" (at -0.72 -3.4 90) (layer "B.Fab") hide
        (effects (font (size 0.7 0.7) (thickness 0.15)) (justify left bottom mirror))
    )
    (fp_text user "License: Apache-2.0" (at -0.72 -4.4 90) (layer "B.Fab") hide
        (effects (font (size 0.7 0.7) (thickness 0.15)) (justify left bottom mirror))
    )
    (fp_text user "Author: Antmicro" (at -0.72 -5.4 90) (layer "B.Fab") hide
        (effects (font (size 0.7 0.7) (thickness 0.15)) (justify left bottom mirror))
    )
    (fp_rect (start -0.72 0.38) (end 0.72 -0.38)
      (stroke (width 0.05) (type solid)) (fill none) (layer "B.CrtYd"))
    (fp_rect (start 0.3 -0.15) (end -0.301 0.149)
      (stroke (width 0.15) (type solid)) (fill none) (layer "B.Fab"))
    (pad "" smd roundrect (at -0.349 0.002 270) (size 0.318 0.36) (layers "B.Paste") (roundrect_rratio 0.25))
    (pad "" smd roundrect (at 0.341 0.002 270) (size 0.318 0.36) (layers "B.Paste") (roundrect_rratio 0.25))
    (pad "1" smd roundrect (at -0.321 0.002 270) (size 0.46 0.4) (layers "B.Cu" "B.Mask") (roundrect_rratio 0.25)
      (net 143 "3V3_SYS") (pintype "passive"))
    (pad "2" smd roundrect (at 0.32 0.002 270) (size 0.46 0.4) (layers "B.Cu" "B.Mask") (roundrect_rratio 0.25)
      (net 9 "GND") (pintype "passive"))
  )
	(footprint "data-center-rdimm-ddr4-tester-footprints:C_0402_1005Metric" (layer "B.Cu")
    (at 226.3 126.3 90)
    (descr "Capacitor SMD 0402")
    (tags "capacitor SMD 0402")
    (property "Author" "Antmicro")
    (property "Dielectric" "")
    (property "License" "Apache-2.0")
    (property "MPN" "C0402C105M4PACTU")
    (property "Manufacturer" "KEMET")
    (property "Sheetfile" "supply.kicad_sch")
    (property "Sheetname" "Supply")
    (property "Val" "1u/16V")
    (property "Voltage" "")
    (property "ki_description" " ")
    (attr smd)
    (fp_text reference "C280" (at 1.45 -0.59 270) (layer "B.SilkS")
        (effects (font (size 0.7 0.7) (thickness 0.15)) (justify left bottom mirror))
    )
    (fp_text value "C_1u_16V_0402" (at 0 -1.4 270) (layer "B.Fab") hide
        (effects (font (size 0.7 0.7) (thickness 0.15)) (justify left bottom mirror))
    )
    (fp_text user "${REFERENCE}" (at -0.932 -3.168 270) (layer "B.Fab") hide
        (effects (font (size 0.7 0.7) (thickness 0.15)) (justify left bottom mirror))
    )
    (fp_text user "License: Apache-2.0" (at -0.932 -5.17 270) (layer "B.Fab") hide
        (effects (font (size 0.7 0.7) (thickness 0.15)) (justify left bottom mirror))
    )
    (fp_text user "Author: Antmicro" (at -0.932 -4.17 270) (layer "B.Fab") hide
        (effects (font (size 0.7 0.7) (thickness 0.15)) (justify left bottom mirror))
    )
    (fp_rect (start -0.94 0.47) (end 0.94 -0.47)
      (stroke (width 0.05) (type solid)) (fill none) (layer "B.CrtYd"))
    (fp_rect (start -0.499 0.249) (end 0.499 -0.249)
      (stroke (width 0.15) (type solid)) (fill none) (layer "B.Fab"))
    (pad "1" smd roundrect (at -0.484 0 90) (size 0.59 0.64) (layers "B.Cu" "B.Paste" "B.Mask") (roundrect_rratio 0.25)
      (net 103 "VIN") (pintype "passive"))
    (pad "2" smd roundrect (at 0.484 0 90) (size 0.59 0.64) (layers "B.Cu" "B.Paste" "B.Mask") (roundrect_rratio 0.25)
      (net 9 "GND") (pintype "passive"))
  )
	(footprint "data-center-rdimm-ddr4-tester-footprints:R_0402_1005Metric" (layer "B.Cu")
    (at 123 97.95)
    (descr "Resistor SMD 0402")
    (tags "resistor SMD 0402")
    (property "Author" "Antmicro")
    (property "License" "Apache-2.0")
    (property "MPN" "CR0402-FX-1002GLF")
    (property "Manufacturer" "Bourns")
    (property "Sheetfile" "supply.kicad_sch")
    (property "Sheetname" "Supply")
    (property "Tolerance" "1%")
    (property "Val" "10k")
    (property "ki_description" "10k resistor in 0402 package with 1% tolerance")
    (attr smd)
    (fp_text reference "R216" (at 1.81 1.32 180) (layer "B.SilkS")
        (effects (font (size 0.7 0.7) (thickness 0.15)) (justify left bottom mirror))
    )
    (fp_text value "R_10k_0402" (at 0 -1.4 180) (layer "B.Fab") hide
        (effects (font (size 0.7 0.7) (thickness 0.15)) (justify left bottom mirror))
    )
    (fp_text user "License: Apache-2.0" (at -0.95 -5.169 180) (layer "B.Fab") hide
        (effects (font (size 0.7 0.7) (thickness 0.15)) (justify left bottom mirror))
    )
    (fp_text user "${REFERENCE}" (at -0.95 -3.168 180) (layer "B.Fab") hide
        (effects (font (size 0.7 0.7) (thickness 0.15)) (justify left bottom mirror))
    )
    (fp_text user "Author: Antmicro" (at -0.95 -4.169 180) (layer "B.Fab") hide
        (effects (font (size 0.7 0.7) (thickness 0.15)) (justify left bottom mirror))
    )
    (fp_rect (start -0.93 0.47) (end 0.93 -0.47)
      (stroke (width 0.05) (type solid)) (fill none) (layer "B.CrtYd"))
    (fp_rect (start -0.5 0.25) (end 0.5 -0.25)
      (stroke (width 0.15) (type solid)) (fill none) (layer "B.Fab"))
    (pad "1" smd roundrect (at -0.485 0) (size 0.59 0.64) (layers "B.Cu" "B.Paste" "B.Mask") (roundrect_rratio 0.25)
      (net 794 "/Supply/SLP_S4") (pintype "passive"))
    (pad "2" smd roundrect (at 0.485 0) (size 0.59 0.64) (layers "B.Cu" "B.Paste" "B.Mask") (roundrect_rratio 0.25)
      (net 9 "GND") (pintype "passive"))
  )
	(footprint "data-center-rdimm-ddr4-tester-footprints:SOT-23-5" (layer "B.Cu")
    (at 229.1 125.8)
    (property "Author" "Antmicro")
    (property "License" "Apache-2.0")
    (property "MPN" "NCP718ASN500T1G")
    (property "Manufacturer" "ON Semiconductor")
    (property "Sheetfile" "supply.kicad_sch")
    (property "Sheetname" "Supply")
    (property "ki_description" "LDO Voltage Regulators 300 MA LOW IQ WIDE INPUT 5.0V")
    (attr smd)
    (fp_text reference "U25" (at -2.5 2.6) (layer "B.SilkS")
        (effects (font (size 0.7 0.7) (thickness 0.15)) (justify right bottom mirror))
    )
    (fp_text value "NCP718ASN500_SOT" (at 0.002 -2.799) (layer "B.Fab") hide
        (effects (font (size 0.7 0.7) (thickness 0.15)) (justify right bottom mirror))
    )
    (fp_text user "${REFERENCE}" (at -1.898 -4.299) (layer "B.Fab") hide
        (effects (font (size 0.7 0.7) (thickness 0.15)) (justify right bottom mirror))
    )
    (fp_text user "Author: Antmicro" (at -1.898 -5.499) (layer "B.Fab") hide
        (effects (font (size 0.7 0.7) (thickness 0.15)) (justify right bottom mirror))
    )
    (fp_text user "License: Apache-2.0" (at -1.898 -6.7) (layer "B.Fab") hide
        (effects (font (size 0.7 0.7) (thickness 0.15)) (justify right bottom mirror))
    )
    (fp_line (start -0.898 -1.699) (end -0.898 -1.4)
      (stroke (width 0.15) (type solid)) (layer "B.SilkS"))
    (fp_line (start -0.898 1.7) (end -0.898 1.4)
      (stroke (width 0.15) (type solid)) (layer "B.SilkS"))
    (fp_line (start -0.898 1.7) (end -0.598 1.7)
      (stroke (width 0.15) (type solid)) (layer "B.SilkS"))
    (fp_line (start -0.598 -1.699) (end -0.898 -1.699)
      (stroke (width 0.15) (type solid)) (layer "B.SilkS"))
    (fp_line (start 0.902 -1.699) (end 0.651 -1.699)
      (stroke (width 0.15) (type solid)) (layer "B.SilkS"))
    (fp_line (start 0.902 -1.4) (end 0.902 -1.699)
      (stroke (width 0.15) (type solid)) (layer "B.SilkS"))
    (fp_line (start 0.902 -0.55) (end 0.902 0.55)
      (stroke (width 0.15) (type solid)) (layer "B.SilkS"))
    (fp_line (start 0.902 1.4) (end 0.902 1.7)
      (stroke (width 0.15) (type solid)) (layer "B.SilkS"))
    (fp_line (start 0.902 1.7) (end 0.602 1.7)
      (stroke (width 0.15) (type solid)) (layer "B.SilkS"))
    (fp_circle (center -1.25 1.5) (end -1.2 1.5)
      (stroke (width 0.15) (type solid)) (fill solid) (layer "B.SilkS"))
    (fp_rect (start 1.9 1.81) (end -1.9 -1.8)
      (stroke (width 0.05) (type solid)) (fill none) (layer "B.CrtYd"))
    (fp_line (start -0.398 1.526) (end -0.874 1.05)
      (stroke (width 0.15) (type solid)) (layer "B.Fab"))
    (fp_rect (start 0.874 -1.523) (end -0.873 1.525)
      (stroke (width 0.15) (type solid)) (fill none) (layer "B.Fab"))
    (pad "1" smd rect (at -1.351 0.951 90) (size 0.55 1) (layers "B.Cu" "B.Paste" "B.Mask")
      (net 103 "VIN") (pinfunction "V_{IN}") (pintype "power_in"))
    (pad "2" smd rect (at -1.351 0 90) (size 0.55 1) (layers "B.Cu" "B.Paste" "B.Mask")
      (net 9 "GND") (pinfunction "GND") (pintype "power_in"))
    (pad "3" smd rect (at -1.351 -0.949 90) (size 0.55 1) (layers "B.Cu" "B.Paste" "B.Mask")
      (net 103 "VIN") (pinfunction "EN") (pintype "input"))
    (pad "4" smd rect (at 1.35 -0.949 90) (size 0.55 1) (layers "B.Cu" "B.Paste" "B.Mask")
      (net 919 "unconnected-(U25-NC-Pad4)") (pinfunction "NC") (pintype "no_connect"))
    (pad "5" smd rect (at 1.35 0.951 90) (size 0.55 1) (layers "B.Cu" "B.Paste" "B.Mask")
      (net 846 "5V_ON_OFF") (pinfunction "V_{OUT}") (pintype "power_out"))
  )
)
